# BASEBOARD_FAB2 (Tioga Pass) — schematic netlist excerpt (pin names and nets, part order shuffled) for the footprints in the layout excerpt that follows; sources: Cadence DE-HDL packaged netlist, KiCad conversion of Wiwynn_Tioga_Pass_MB.brd

R4E7  RES  10.0 1% CHIP  pkg 0402  page 213 : A = VSENSE_PVCCIO_CPU1_AVSP ; B = VR_PVCCIO_CPU1_AVSP
C7A11  CAP  1.0UF 16V 10% X6S  pkg 0402  page 219 : A = VR_FET_SW_P12V_STBY_PVDDQ_DEF ; B = GND
C9F9  CAP  1000PF 50V 10% EMPTY  pkg 0402LF  page 238 : A = PWRGD_P1V2_BMC_STBY ; B = GND

(kicad_pcb
	(version 20260206)
	(generator "pcbnew")
	(generator_version "10.0")
	(general
		(thickness 1.6)
		(legacy_teardrops no)
	)
	(paper "A4")
	(title_block
		(title "Wiwynn_Tioga_Pass_MB.brd")
		(comment 1 "Tioga Pass / footprints 209-211 of 4770")
	)
	(layers
		(0 "F.Cu" signal "TOP")
		(4 "In1.Cu" signal "L2GND")
		(6 "In2.Cu" signal "L3")
		(8 "In3.Cu" signal "L4GND")
		(10 "In4.Cu" signal "L5")
		(12 "In5.Cu" signal "L6GND")
		(14 "In6.Cu" signal "L7VCC")
		(16 "In7.Cu" signal "L8VCC")
		(18 "In8.Cu" signal "L9GND")
		(20 "In9.Cu" signal "L10")
		(22 "In10.Cu" signal "L11GND")
		(24 "In11.Cu" signal "L12")
		(26 "In12.Cu" signal "L13GND")
		(2 "B.Cu" signal "BOTTOM")
		(9 "F.Adhes" user "F.Adhesive")
		(11 "B.Adhes" user "B.Adhesive")
		(13 "F.Paste" user "Package Geometry/Pastemask Top")
		(15 "B.Paste" user "Package Geometry/Pastemask Bottom")
		(5 "F.SilkS" user "Ref Des/Silkscreen Top")
		(7 "B.SilkS" user "Ref Des/Silkscreen Bottom")
		(1 "F.Mask" user "Board Geometry/Soldermask Top")
		(3 "B.Mask" user "Board Geometry/Soldermask Bottom")
		(17 "Dwgs.User" user "User.Drawings")
		(19 "Cmts.User" user "User.Comments")
		(21 "Eco1.User" user "User.Eco1")
		(23 "Eco2.User" user "User.Eco2")
		(25 "Edge.Cuts" user "Board Geometry/Outline")
		(27 "Margin" user)
		(31 "F.CrtYd" user "Package Geometry/Place Bound Top")
		(29 "B.CrtYd" user "Package Geometry/Place Bound Bottom")
		(35 "F.Fab" user "Ref Des/Assembly Top")
		(33 "B.Fab" user "Ref Des/Assembly Bottom")
	)
	(footprint ""
		(layer "F.Cu")
		(at 352.1075 -150.368 90)
		(property "Reference" "C7A11"
			(at 0 0 90)
			(layer "F.SilkS")
			(hide yes)
			(effects
				(font
					(size 1.27 1.27)
				)
			)
		)
		(property "Value" ""
			(at 0 0 90)
			(layer "F.Fab")
			(effects
				(font
					(size 1.27 1.27)
				)
			)
		)
		(duplicate_pad_numbers_are_jumpers no)
		(fp_poly
			(pts
				(xy 0.3048 -0.1016) (xy 0.3048 0.9906) (xy -0.3048 0.9906) (xy -0.3048 -0.1016)
			)
			(stroke
				(width 0)
				(type default)
			)
			(fill no)
			(layer "F.CrtYd")
		)
		(fp_line
			(start 0.3048 -0.1016)
			(end -0.3048 -0.1016)
			(stroke
				(width 0.1)
				(type default)
			)
			(layer "F.Fab")
		)
		(fp_line
			(start -0.3048 -0.1016)
			(end -0.3048 0.9906)
			(stroke
				(width 0.1)
				(type default)
			)
			(layer "F.Fab")
		)
		(fp_line
			(start 0.3048 0.9906)
			(end 0.3048 -0.1016)
			(stroke
				(width 0.1)
				(type default)
			)
			(layer "F.Fab")
		)
		(fp_line
			(start -0.3048 0.9906)
			(end 0.3048 0.9906)
			(stroke
				(width 0.1)
				(type default)
			)
			(layer "F.Fab")
		)
		(pad "1" smd rect
			(at 0 0 90)
			(size 0.508 0.508)
			(layers "F.Cu" "F.Mask" "F.Paste")
			(net "VR_FET_SW_P12V_STBY_PVDDQ_DEF")
		)
		(pad "2" smd rect
			(at 0 0.889 90)
			(size 0.508 0.508)
			(layers "F.Cu" "F.Mask" "F.Paste")
			(net "GND")
		)
		(zone
			(layer "F.Cu")
			(hatch none 0.5)
			(connect_pads
				(clearance 0)
			)
			(min_thickness 0.25)
			(keepout
				(tracks allowed)
				(vias not_allowed)
				(pads allowed)
				(copperpour not_allowed)
				(footprints allowed)
			)
			(placement
				(enabled no)
				(sheetname "")
			)
			(fill
				(thermal_gap 0.5)
				(thermal_bridge_width 0.5)
				(island_removal_mode 0)
			)
			(polygon
				(pts
					(xy 352.3615 -150.114) (xy 352.3615 -150.622) (xy 352.7425 -150.622) (xy 352.7425 -150.114)
				)
			)
		)
		(zone
			(layer "F.Cu")
			(hatch none 0.5)
			(connect_pads
				(clearance 0)
			)
			(min_thickness 0.25)
			(keepout
				(tracks not_allowed)
				(vias allowed)
				(pads allowed)
				(copperpour not_allowed)
				(footprints allowed)
			)
			(placement
				(enabled no)
				(sheetname "")
			)
			(fill
				(thermal_gap 0.5)
				(thermal_bridge_width 0.5)
				(island_removal_mode 0)
			)
			(polygon
				(pts
					(xy 352.7425 -150.114) (xy 352.7425 -150.622) (xy 352.3615 -150.622) (xy 352.3615 -150.114)
				)
			)
		)
	)
	(footprint ""
		(layer "F.Cu")
		(at 463.003392 -37.956998)
		(property "Reference" "C9F9"
			(at 0 0 0)
			(layer "F.SilkS")
			(hide yes)
			(effects
				(font
					(size 1.27 1.27)
				)
			)
		)
		(property "Value" ""
			(at 0 0 0)
			(layer "F.Fab")
			(effects
				(font
					(size 1.27 1.27)
				)
			)
		)
		(duplicate_pad_numbers_are_jumpers no)
		(fp_poly
			(pts
				(xy 0.3048 -0.1016) (xy 0.3048 0.9906) (xy -0.3048 0.9906) (xy -0.3048 -0.1016)
			)
			(stroke
				(width 0)
				(type default)
			)
			(fill no)
			(layer "F.CrtYd")
		)
		(fp_line
			(start -0.3048 -0.1016)
			(end -0.3048 0.9906)
			(stroke
				(width 0.1)
				(type default)
			)
			(layer "F.Fab")
		)
		(fp_line
			(start -0.3048 0.9906)
			(end 0.3048 0.9906)
			(stroke
				(width 0.1)
				(type default)
			)
			(layer "F.Fab")
		)
		(fp_line
			(start 0.3048 -0.1016)
			(end -0.3048 -0.1016)
			(stroke
				(width 0.1)
				(type default)
			)
			(layer "F.Fab")
		)
		(fp_line
			(start 0.3048 0.9906)
			(end 0.3048 -0.1016)
			(stroke
				(width 0.1)
				(type default)
			)
			(layer "F.Fab")
		)
		(pad "1" smd rect
			(at 0 0)
			(size 0.508 0.508)
			(layers "F.Cu" "F.Mask" "F.Paste")
			(net "PWRGD_P1V2_BMC_STBY")
		)
		(pad "2" smd rect
			(at 0 0.889)
			(size 0.508 0.508)
			(layers "F.Cu" "F.Mask" "F.Paste")
			(net "GND")
		)
		(zone
			(layer "F.Cu")
			(hatch none 0.5)
			(connect_pads
				(clearance 0)
			)
			(min_thickness 0.25)
			(keepout
				(tracks allowed)
				(vias not_allowed)
				(pads allowed)
				(copperpour not_allowed)
				(footprints allowed)
			)
			(placement
				(enabled no)
				(sheetname "")
			)
			(fill
				(thermal_gap 0.5)
				(thermal_bridge_width 0.5)
				(island_removal_mode 0)
			)
			(polygon
				(pts
					(xy 462.749392 -37.702998) (xy 463.257392 -37.702998) (xy 463.257392 -37.321998) (xy 462.749392 -37.321998)
				)
			)
		)
		(zone
			(layer "F.Cu")
			(hatch none 0.5)
			(connect_pads
				(clearance 0)
			)
			(min_thickness 0.25)
			(keepout
				(tracks not_allowed)
				(vias allowed)
				(pads allowed)
				(copperpour not_allowed)
				(footprints allowed)
			)
			(placement
				(enabled no)
				(sheetname "")
			)
			(fill
				(thermal_gap 0.5)
				(thermal_bridge_width 0.5)
				(island_removal_mode 0)
			)
			(polygon
				(pts
					(xy 462.749392 -37.321998) (xy 463.257392 -37.321998) (xy 463.257392 -37.702998) (xy 462.749392 -37.702998)
				)
			)
		)
	)
	(footprint ""
		(layer "F.Cu")
		(at 164.084 -64.9224 180)
		(property "Reference" "R4E7"
			(at 0 0 180)
			(layer "F.SilkS")
			(hide yes)
			(effects
				(font
					(size 1.27 1.27)
				)
			)
		)
		(property "Value" ""
			(at 0 0 180)
			(layer "F.Fab")
			(effects
				(font
					(size 1.27 1.27)
				)
			)
		)
		(duplicate_pad_numbers_are_jumpers no)
		(fp_poly
			(pts
				(xy -0.2794 -0.1016) (xy 0.2794 -0.1016) (xy 0.2794 0.9906) (xy -0.2794 0.9906)
			)
			(stroke
				(width 0)
				(type default)
			)
			(fill no)
			(layer "F.CrtYd")
		)
		(fp_line
			(start 0.2794 0.9906)
			(end 0.2794 -0.1016)
			(stroke
				(width 0.1)
				(type default)
			)
			(layer "F.Fab")
		)
		(fp_line
			(start 0.2794 -0.1016)
			(end -0.2794 -0.1016)
			(stroke
				(width 0.1)
				(type default)
			)
			(layer "F.Fab")
		)
		(fp_line
			(start -0.2794 0.9906)
			(end 0.2794 0.9906)
			(stroke
				(width 0.1)
				(type default)
			)
			(layer "F.Fab")
		)
		(fp_line
			(start -0.2794 -0.1016)
			(end -0.2794 0.9906)
			(stroke
				(width 0.1)
				(type default)
			)
			(layer "F.Fab")
		)
		(pad "1" smd rect
			(at 0 0 180)
			(size 0.508 0.508)
			(layers "F.Cu" "F.Mask" "F.Paste")
			(net "VSENSE_PVCCIO_CPU1_AVSP")
		)
		(pad "2" smd rect
			(at 0 0.889 180)
			(size 0.508 0.508)
			(layers "F.Cu" "F.Mask" "F.Paste")
			(net "VR_PVCCIO_CPU1_AVSP")
		)
		(zone
			(layer "F.Cu")
			(hatch none 0.5)
			(connect_pads
				(clearance 0)
			)
			(min_thickness 0.25)
			(keepout
				(tracks not_allowed)
				(vias allowed)
				(pads allowed)
				(copperpour not_allowed)
				(footprints allowed)
			)
			(placement
				(enabled no)
				(sheetname "")
			)
			(fill
				(thermal_gap 0.5)
				(thermal_bridge_width 0.5)
				(island_removal_mode 0)
			)
			(polygon
				(pts
					(xy 164.338 -65.5574) (xy 163.83 -65.5574) (xy 163.83 -65.1764) (xy 164.338 -65.1764)
				)
			)
		)
		(zone
			(layer "F.Cu")
			(hatch none 0.5)
			(connect_pads
				(clearance 0)
			)
			(min_thickness 0.25)
			(keepout
				(tracks allowed)
				(vias not_allowed)
				(pads allowed)
				(copperpour not_allowed)
				(footprints allowed)
			)
			(placement
				(enabled no)
				(sheetname "")
			)
			(fill
				(thermal_gap 0.5)
				(thermal_bridge_width 0.5)
				(island_removal_mode 0)
			)
			(polygon
				(pts
					(xy 164.338 -65.1764) (xy 163.83 -65.1764) (xy 163.83 -65.5574) (xy 164.338 -65.5574)
				)
			)
		)
	)
)
